# S9S_MB_2U (Grand Teton) — schematic netlist excerpt (pin names and nets, part order shuffled) for the footprints in the layout excerpt that follows; sources: Cadence DE-HDL packaged netlist, KiCad conversion of 03242023_DA0F0TMBIJ0_F0T_Motherboard_J_brd_V01_OCP.brd

J83  PICOPROBE_BXA  DELTA-L 4.0 EMPTY  pkg TRIANG_LAUNCH_3PXB  page 308
  \1_p\  = DELTA_L_85_10INCH_IN1_DN
  \2_n\  = DELTA_L_85_10INCH_IN1_DP
  \3_g\  = DELTA_L_GND_1

(kicad_pcb
	(version 20260206)
	(generator "pcbnew")
	(generator_version "10.0")
	(general
		(thickness 1.6)
		(legacy_teardrops no)
	)
	(paper "A4")
	(title_block
		(title "03242023_DA0F0TMBIJ0_F0T_Motherboard_J_brd_V01_OCP.brd")
		(comment 1 "Grand Teton / footprints 2373-2373 of 6105")
	)
	(layers
		(0 "F.Cu" signal "TOP")
		(4 "In1.Cu" signal "GND")
		(6 "In2.Cu" signal "IN1")
		(8 "In3.Cu" signal "GND1")
		(10 "In4.Cu" signal "IN2")
		(12 "In5.Cu" signal "GND2")
		(14 "In6.Cu" signal "IN3")
		(16 "In7.Cu" signal "GND3")
		(18 "In8.Cu" signal "VCC")
		(20 "In9.Cu" signal "VCC1")
		(22 "In10.Cu" signal "GND4")
		(24 "In11.Cu" signal "IN4")
		(26 "In12.Cu" signal "GND5")
		(28 "In13.Cu" signal "IN5")
		(30 "In14.Cu" signal "GND6")
		(32 "In15.Cu" signal "IN6")
		(34 "In16.Cu" signal "GND7")
		(2 "B.Cu" signal "BOTTOM")
		(9 "F.Adhes" user "F.Adhesive")
		(11 "B.Adhes" user "B.Adhesive")
		(13 "F.Paste" user "Package Geometry/Pastemask Top")
		(15 "B.Paste" user "Package Geometry/Pastemask Bottom")
		(5 "F.SilkS" user "Ref Des/Silkscreen Top")
		(7 "B.SilkS" user "Ref Des/Silkscreen Bottom")
		(1 "F.Mask" user "Board Geometry/Soldermask Top")
		(3 "B.Mask" user "Board Geometry/Soldermask Bottom")
		(17 "Dwgs.User" user "User.Drawings")
		(19 "Cmts.User" user "User.Comments")
		(21 "Eco1.User" user "User.Eco1")
		(23 "Eco2.User" user "User.Eco2")
		(25 "Edge.Cuts" user "Board Geometry/Outline")
		(27 "Margin" user)
		(31 "F.CrtYd" user "Package Geometry/Place Bound Top")
		(29 "B.CrtYd" user "Package Geometry/Place Bound Bottom")
		(35 "F.Fab" user "Ref Des/Assembly Top")
		(33 "B.Fab" user "Ref Des/Assembly Bottom")
	)
	(footprint ""
		(layer "F.Cu")
		(at 329.240388 0.383794 180)
		(property "Reference" "J83"
			(at -4.415282 -1.140206 90)
			(unlocked yes)
			(layer "F.SilkS")
			(effects
				(font
					(size 0.7874 0.5842)
					(thickness 0.1524)
				)
				(justify left)
			)
		)
		(property "Value" ""
			(at 0 0 180)
			(layer "F.Fab")
			(effects
				(font
					(size 1.27 1.27)
				)
			)
		)
		(duplicate_pad_numbers_are_jumpers no)
		(fp_line
			(start 1.2192 2.1082)
			(end -1.2192 2.1082)
			(stroke
				(width 0.1524)
				(type default)
			)
			(layer "F.SilkS")
		)
		(fp_line
			(start 1.2192 -2.1082)
			(end 1.2192 2.1082)
			(stroke
				(width 0.1524)
				(type default)
			)
			(layer "F.SilkS")
		)
		(fp_line
			(start -1.2192 2.1082)
			(end -1.2192 -2.1082)
			(stroke
				(width 0.1524)
				(type default)
			)
			(layer "F.SilkS")
		)
		(fp_line
			(start -1.2192 -2.1082)
			(end 1.2192 -2.1082)
			(stroke
				(width 0.1524)
				(type default)
			)
			(layer "F.SilkS")
		)
		(pad "" np_thru_hole circle
			(at -2.8829 -1.27 90)
			(size 1.0414 1.0414)
			(drill 1.0414)
			(layers "*.Cu" "*.Mask")
			(clearance 0.381)
			(thermal_gap 0.381)
		)
		(pad "" np_thru_hole circle
			(at -2.8829 1.27 90)
			(size 1.0414 1.0414)
			(drill 1.0414)
			(layers "*.Cu" "*.Mask")
			(clearance 0.381)
			(thermal_gap 0.381)
		)
		(pad "" np_thru_hole circle
			(at 3.4671 -1.27 90)
			(size 1.0414 1.0414)
			(drill 1.0414)
			(layers "*.Cu" "*.Mask")
			(clearance 0.381)
			(thermal_gap 0.381)
		)
		(pad "" np_thru_hole circle
			(at 3.4671 1.27 90)
			(size 1.0414 1.0414)
			(drill 1.0414)
			(layers "*.Cu" "*.Mask")
			(clearance 0.381)
			(thermal_gap 0.381)
		)
		(pad "1" smd rect
			(at 0.8255 -0.249936 90)
			(size 0.3048 0.508)
			(layers "F.Cu" "F.Mask" "F.Paste")
			(net "DELTA_L_85_10INCH_IN1_DN")
		)
		(pad "2" smd rect
			(at 0.8255 0.249936 90)
			(size 0.3048 0.508)
			(layers "F.Cu" "F.Mask" "F.Paste")
			(net "DELTA_L_85_10INCH_IN1_DP")
		)
		(pad "3" smd circle
			(at 0 0 180)
			(size 0 0)
			(layers "F.Cu" "F.Mask" "F.Paste")
			(net "DELTA_L_GND_1")
		)
		(zone
			(layer "F.Cu")
			(hatch none 0.5)
			(connect_pads
				(clearance 0)
			)
			(min_thickness 0.25)
			(keepout
				(tracks not_allowed)
				(vias allowed)
				(pads allowed)
				(copperpour not_allowed)
				(footprints allowed)
			)
			(placement
				(enabled no)
				(sheetname "")
			)
			(fill
				(thermal_gap 0.5)
				(thermal_bridge_width 0.5)
				(island_removal_mode 0)
			)
			(polygon
				(pts
					(xy 328.122788 0.932434) (xy 328.122788 0.83693) (xy 328.719688 0.83693) (xy 328.719688 0.43053)
					(xy 328.122788 0.43053) (xy 328.122788 0.337058) (xy 328.719688 0.337058) (xy 328.719688 -0.069342)
					(xy 328.122788 -0.069342) (xy 328.122788 -0.164846) (xy 328.821288 -0.164846) (xy 328.821288 0.932434)
				)
			)
		)
		(zone
			(layers "F.Cu" "B.Cu" "In1.Cu" "In2.Cu" "In3.Cu" "In4.Cu" "In5.Cu" "In6.Cu"
				"In7.Cu" "In8.Cu" "In9.Cu" "In10.Cu" "In11.Cu" "In12.Cu" "In13.Cu" "In14.Cu"
				"In15.Cu" "In16.Cu"
			)
			(hatch none 0.5)
			(connect_pads
				(clearance 0)
			)
			(min_thickness 0.25)
			(keepout
				(tracks not_allowed)
				(vias allowed)
				(pads allowed)
				(copperpour not_allowed)
				(footprints allowed)
			)
			(placement
				(enabled no)
				(sheetname "")
			)
			(fill
				(thermal_gap 0.5)
				(thermal_bridge_width 0.5)
				(island_removal_mode 0)
			)
			(polygon
				(pts
					(arc
						(start 326.700388 -0.886206)
						(mid 324.846188 -0.886206)
						(end 326.700388 -0.886206)
					)
				)
			)
		)
		(zone
			(layers "F.Cu" "B.Cu" "In1.Cu" "In2.Cu" "In3.Cu" "In4.Cu" "In5.Cu" "In6.Cu"
				"In7.Cu" "In8.Cu" "In9.Cu" "In10.Cu" "In11.Cu" "In12.Cu" "In13.Cu" "In14.Cu"
				"In15.Cu" "In16.Cu"
			)
			(hatch none 0.5)
			(connect_pads
				(clearance 0)
			)
			(min_thickness 0.25)
			(keepout
				(tracks not_allowed)
				(vias allowed)
				(pads allowed)
				(copperpour not_allowed)
				(footprints allowed)
			)
			(placement
				(enabled no)
				(sheetname "")
			)
			(fill
				(thermal_gap 0.5)
				(thermal_bridge_width 0.5)
				(island_removal_mode 0)
			)
			(polygon
				(pts
					(arc
						(start 326.700388 1.653794)
						(mid 324.846188 1.653794)
						(end 326.700388 1.653794)
					)
				)
			)
		)
		(zone
			(layers "F.Cu" "B.Cu" "In1.Cu" "In2.Cu" "In3.Cu" "In4.Cu" "In5.Cu" "In6.Cu"
				"In7.Cu" "In8.Cu" "In9.Cu" "In10.Cu" "In11.Cu" "In12.Cu" "In13.Cu" "In14.Cu"
				"In15.Cu" "In16.Cu"
			)
			(hatch none 0.5)
			(connect_pads
				(clearance 0)
			)
			(min_thickness 0.25)
			(keepout
				(tracks not_allowed)
				(vias allowed)
				(pads allowed)
				(copperpour not_allowed)
				(footprints allowed)
			)
			(placement
				(enabled no)
				(sheetname "")
			)
			(fill
				(thermal_gap 0.5)
				(thermal_bridge_width 0.5)
				(island_removal_mode 0)
			)
			(polygon
				(pts
					(arc
						(start 333.050388 -0.886206)
						(mid 331.196188 -0.886206)
						(end 333.050388 -0.886206)
					)
				)
			)
		)
		(zone
			(layers "F.Cu" "B.Cu" "In1.Cu" "In2.Cu" "In3.Cu" "In4.Cu" "In5.Cu" "In6.Cu"
				"In7.Cu" "In8.Cu" "In9.Cu" "In10.Cu" "In11.Cu" "In12.Cu" "In13.Cu" "In14.Cu"
				"In15.Cu" "In16.Cu"
			)
			(hatch none 0.5)
			(connect_pads
				(clearance 0)
			)
			(min_thickness 0.25)
			(keepout
				(tracks not_allowed)
				(vias allowed)
				(pads allowed)
				(copperpour not_allowed)
				(footprints allowed)
			)
			(placement
				(enabled no)
				(sheetname "")
			)
			(fill
				(thermal_gap 0.5)
				(thermal_bridge_width 0.5)
				(island_removal_mode 0)
			)
			(polygon
				(pts
					(arc
						(start 333.050388 1.653794)
						(mid 331.196188 1.653794)
						(end 333.050388 1.653794)
					)
				)
			)
		)
	)
)
